# T6G (Grand Teton) — schematic netlist excerpt (pin names and nets, part order shuffled) for the footprints in the layout excerpt that follows; sources: Cadence DE-HDL packaged netlist, KiCad conversion of 04192023_DAF0TMB3IC0_F0TG_MB_C_brd_V02_OCP.brd

R227  Q_RES  33 5% CHIP  pkg 0402LF  page 82 : A = FM_PVDD11_S3_P0_EN ; B = PVDD11_S3_P0_EN
R4561  Q_RES  100K 1% CHIP  pkg 0402LF  page 125 : A = P3V3_AUX ; B = SWB_HSC_PWRGD_ISO

(kicad_pcb
	(version 20260206)
	(generator "pcbnew")
	(generator_version "10.0")
	(general
		(thickness 1.6)
		(legacy_teardrops no)
	)
	(paper "A4")
	(title_block
		(title "04192023_DAF0TMB3IC0_F0TG_MB_C_brd_V02_OCP.brd")
		(comment 1 "Grand Teton / footprints 3403-3404 of 8354")
	)
	(layers
		(0 "F.Cu" signal "TOP")
		(4 "In1.Cu" signal "GND")
		(6 "In2.Cu" signal "IN1")
		(8 "In3.Cu" signal "GND1")
		(10 "In4.Cu" signal "IN2")
		(12 "In5.Cu" signal "GND2")
		(14 "In6.Cu" signal "IN3")
		(16 "In7.Cu" signal "GND3")
		(18 "In8.Cu" signal "VCC")
		(20 "In9.Cu" signal "VCC1")
		(22 "In10.Cu" signal "GND4")
		(24 "In11.Cu" signal "IN4")
		(26 "In12.Cu" signal "GND5")
		(28 "In13.Cu" signal "IN5")
		(30 "In14.Cu" signal "GND6")
		(32 "In15.Cu" signal "IN6")
		(34 "In16.Cu" signal "GND7")
		(2 "B.Cu" signal "BOTTOM")
		(9 "F.Adhes" user "F.Adhesive")
		(11 "B.Adhes" user "B.Adhesive")
		(13 "F.Paste" user "Package Geometry/Pastemask Top")
		(15 "B.Paste" user "Package Geometry/Pastemask Bottom")
		(5 "F.SilkS" user "Ref Des/Silkscreen Top")
		(7 "B.SilkS" user "Ref Des/Silkscreen Bottom")
		(1 "F.Mask" user "Board Geometry/Soldermask Top")
		(3 "B.Mask" user "Board Geometry/Soldermask Bottom")
		(17 "Dwgs.User" user "User.Drawings")
		(19 "Cmts.User" user "User.Comments")
		(21 "Eco1.User" user "User.Eco1")
		(23 "Eco2.User" user "User.Eco2")
		(25 "Edge.Cuts" user "Board Geometry/Outline")
		(27 "Margin" user)
		(31 "F.CrtYd" user "Package Geometry/Place Bound Top")
		(29 "B.CrtYd" user "Package Geometry/Place Bound Bottom")
		(35 "F.Fab" user "Ref Des/Assembly Top")
		(33 "B.Fab" user "Ref Des/Assembly Bottom")
	)
	(footprint ""
		(layer "F.Cu")
		(at 200.939908 -105.497376)
		(property "Reference" "R227"
			(at 0 0 0)
			(layer "F.SilkS")
			(hide yes)
			(effects
				(font
					(size 1.27 1.27)
				)
			)
		)
		(property "Value" ""
			(at 0 0 0)
			(layer "F.Fab")
			(effects
				(font
					(size 1.27 1.27)
				)
			)
		)
		(duplicate_pad_numbers_are_jumpers no)
		(fp_line
			(start -0.7874 -0.4064)
			(end 0.7874 -0.4064)
			(stroke
				(width 0.1524)
				(type default)
			)
			(layer "F.SilkS")
		)
		(fp_line
			(start -0.7874 0.4064)
			(end -0.7874 -0.4064)
			(stroke
				(width 0.1524)
				(type default)
			)
			(layer "F.SilkS")
		)
		(fp_line
			(start 0.7874 -0.4064)
			(end 0.7874 0.4064)
			(stroke
				(width 0.1524)
				(type default)
			)
			(layer "F.SilkS")
		)
		(fp_line
			(start 0.7874 0.4064)
			(end -0.7874 0.4064)
			(stroke
				(width 0.1524)
				(type default)
			)
			(layer "F.SilkS")
		)
		(fp_line
			(start -0.67945 -0.305054)
			(end -0.12065 -0.305054)
			(stroke
				(width 0.1)
				(type default)
			)
			(layer "F.Fab")
		)
		(fp_line
			(start -0.67945 0.3048)
			(end -0.67945 -0.305054)
			(stroke
				(width 0.1)
				(type default)
			)
			(layer "F.Fab")
		)
		(fp_line
			(start -0.12065 -0.305054)
			(end -0.12065 -0.2794)
			(stroke
				(width 0.1)
				(type default)
			)
			(layer "F.Fab")
		)
		(fp_line
			(start -0.12065 -0.2794)
			(end 0.12065 -0.2794)
			(stroke
				(width 0.1)
				(type default)
			)
			(layer "F.Fab")
		)
		(fp_line
			(start -0.12065 0.2794)
			(end -0.12065 0.3048)
			(stroke
				(width 0.1)
				(type default)
			)
			(layer "F.Fab")
		)
		(fp_line
			(start -0.12065 0.3048)
			(end -0.67945 0.3048)
			(stroke
				(width 0.1)
				(type default)
			)
			(layer "F.Fab")
		)
		(fp_line
			(start 0.120396 0.2794)
			(end -0.12065 0.2794)
			(stroke
				(width 0.1)
				(type default)
			)
			(layer "F.Fab")
		)
		(fp_line
			(start 0.120396 0.3048)
			(end 0.120396 0.2794)
			(stroke
				(width 0.1)
				(type default)
			)
			(layer "F.Fab")
		)
		(fp_line
			(start 0.12065 -0.3048)
			(end 0.67945 -0.3048)
			(stroke
				(width 0.1)
				(type default)
			)
			(layer "F.Fab")
		)
		(fp_line
			(start 0.12065 -0.2794)
			(end 0.12065 -0.3048)
			(stroke
				(width 0.1)
				(type default)
			)
			(layer "F.Fab")
		)
		(fp_line
			(start 0.67945 -0.3048)
			(end 0.67945 0.3048)
			(stroke
				(width 0.1)
				(type default)
			)
			(layer "F.Fab")
		)
		(fp_line
			(start 0.67945 0.3048)
			(end 0.120396 0.3048)
			(stroke
				(width 0.1)
				(type default)
			)
			(layer "F.Fab")
		)
		(pad "1" smd circle
			(at -0.40005 0)
			(size 0 0)
			(layers "F.Cu" "F.Mask" "F.Paste")
			(net "FM_PVDD11_S3_P0_EN")
		)
		(pad "2" smd circle
			(at 0.40005 0)
			(size 0 0)
			(layers "F.Cu" "F.Mask" "F.Paste")
			(net "PVDD11_S3_P0_EN")
		)
	)
	(footprint ""
		(layer "F.Cu")
		(at 353.185222 -425.295314 180)
		(property "Reference" "R4561"
			(at 0 0 180)
			(layer "F.SilkS")
			(hide yes)
			(effects
				(font
					(size 1.27 1.27)
				)
			)
		)
		(property "Value" ""
			(at 0 0 180)
			(layer "F.Fab")
			(effects
				(font
					(size 1.27 1.27)
				)
			)
		)
		(duplicate_pad_numbers_are_jumpers no)
		(fp_line
			(start 0.7874 0.4064)
			(end -0.7874 0.4064)
			(stroke
				(width 0.1524)
				(type default)
			)
			(layer "F.SilkS")
		)
		(fp_line
			(start 0.7874 -0.4064)
			(end 0.7874 0.4064)
			(stroke
				(width 0.1524)
				(type default)
			)
			(layer "F.SilkS")
		)
		(fp_line
			(start -0.7874 0.4064)
			(end -0.7874 -0.4064)
			(stroke
				(width 0.1524)
				(type default)
			)
			(layer "F.SilkS")
		)
		(fp_line
			(start -0.7874 -0.4064)
			(end 0.7874 -0.4064)
			(stroke
				(width 0.1524)
				(type default)
			)
			(layer "F.SilkS")
		)
		(fp_line
			(start 0.67945 0.3048)
			(end 0.120396 0.3048)
			(stroke
				(width 0.1)
				(type default)
			)
			(layer "F.Fab")
		)
		(fp_line
			(start 0.67945 -0.3048)
			(end 0.67945 0.3048)
			(stroke
				(width 0.1)
				(type default)
			)
			(layer "F.Fab")
		)
		(fp_line
			(start 0.12065 -0.2794)
			(end 0.12065 -0.3048)
			(stroke
				(width 0.1)
				(type default)
			)
			(layer "F.Fab")
		)
		(fp_line
			(start 0.12065 -0.3048)
			(end 0.67945 -0.3048)
			(stroke
				(width 0.1)
				(type default)
			)
			(layer "F.Fab")
		)
		(fp_line
			(start 0.120396 0.3048)
			(end 0.120396 0.2794)
			(stroke
				(width 0.1)
				(type default)
			)
			(layer "F.Fab")
		)
		(fp_line
			(start 0.120396 0.2794)
			(end -0.12065 0.2794)
			(stroke
				(width 0.1)
				(type default)
			)
			(layer "F.Fab")
		)
		(fp_line
			(start -0.12065 0.3048)
			(end -0.67945 0.3048)
			(stroke
				(width 0.1)
				(type default)
			)
			(layer "F.Fab")
		)
		(fp_line
			(start -0.12065 0.2794)
			(end -0.12065 0.3048)
			(stroke
				(width 0.1)
				(type default)
			)
			(layer "F.Fab")
		)
		(fp_line
			(start -0.12065 -0.2794)
			(end 0.12065 -0.2794)
			(stroke
				(width 0.1)
				(type default)
			)
			(layer "F.Fab")
		)
		(fp_line
			(start -0.12065 -0.305054)
			(end -0.12065 -0.2794)
			(stroke
				(width 0.1)
				(type default)
			)
			(layer "F.Fab")
		)
		(fp_line
			(start -0.67945 0.3048)
			(end -0.67945 -0.305054)
			(stroke
				(width 0.1)
				(type default)
			)
			(layer "F.Fab")
		)
		(fp_line
			(start -0.67945 -0.305054)
			(end -0.12065 -0.305054)
			(stroke
				(width 0.1)
				(type default)
			)
			(layer "F.Fab")
		)
		(pad "1" smd circle
			(at -0.40005 0 180)
			(size 0 0)
			(layers "F.Cu" "F.Mask" "F.Paste")
			(net "P3V3_AUX")
		)
		(pad "2" smd circle
			(at 0.40005 0 180)
			(size 0 0)
			(layers "F.Cu" "F.Mask" "F.Paste")
			(net "SWB_HSC_PWRGD_ISO")
		)
	)
)
